(kicad_pcb
	(version 20260206)
	(generator "pcbnew")
	(generator_version "10.0")
	(general
		(thickness 1.6)
		(legacy_teardrops no)
	)
	(paper "A4")
	(title_block
		(title "03242023_DA0F0TMBIJ0_F0T_Motherboard_J_brd_V01_OCP.brd")
		(comment 1 "Grand Teton / footprints 2775-2780 of 6105")
	)
	(layers
		(0 "F.Cu" signal "TOP")
		(4 "In1.Cu" signal "GND")
		(6 "In2.Cu" signal "IN1")
		(8 "In3.Cu" signal "GND1")
		(10 "In4.Cu" signal "IN2")
		(12 "In5.Cu" signal "GND2")
		(14 "In6.Cu" signal "IN3")
		(16 "In7.Cu" signal "GND3")
		(18 "In8.Cu" signal "VCC")
		(20 "In9.Cu" signal "VCC1")
		(22 "In10.Cu" signal "GND4")
		(24 "In11.Cu" signal "IN4")
		(26 "In12.Cu" signal "GND5")
		(28 "In13.Cu" signal "IN5")
		(30 "In14.Cu" signal "GND6")
		(32 "In15.Cu" signal "IN6")
		(34 "In16.Cu" signal "GND7")
		(2 "B.Cu" signal "BOTTOM")
		(9 "F.Adhes" user "F.Adhesive")
		(11 "B.Adhes" user "B.Adhesive")
		(13 "F.Paste" user "Package Geometry/Pastemask Top")
		(15 "B.Paste" user "Package Geometry/Pastemask Bottom")
		(5 "F.SilkS" user "Ref Des/Silkscreen Top")
		(7 "B.SilkS" user "Ref Des/Silkscreen Bottom")
		(1 "F.Mask" user "Board Geometry/Soldermask Top")
		(3 "B.Mask" user "Board Geometry/Soldermask Bottom")
		(17 "Dwgs.User" user "User.Drawings")
		(19 "Cmts.User" user "User.Comments")
		(21 "Eco1.User" user "User.Eco1")
		(23 "Eco2.User" user "User.Eco2")
		(25 "Edge.Cuts" user "Board Geometry/Outline")
		(27 "Margin" user)
		(31 "F.CrtYd" user "Package Geometry/Place Bound Top")
		(29 "B.CrtYd" user "Package Geometry/Place Bound Bottom")
		(35 "F.Fab" user "Ref Des/Assembly Top")
		(33 "B.Fab" user "Ref Des/Assembly Bottom")
	)
	(footprint ""
		(layer "F.Cu")
		(at 32.353758 -138.03757 90)
		(property "Reference" "PR4242"
			(at 0 0 90)
			(layer "F.SilkS")
			(hide yes)
			(effects
				(font
					(size 1.27 1.27)
				)
			)
		)
		(property "Value" ""
			(at 0 0 90)
			(layer "F.Fab")
			(effects
				(font
					(size 1.27 1.27)
				)
			)
		)
		(duplicate_pad_numbers_are_jumpers no)
		(fp_line
			(start 0.7874 -0.4064)
			(end 0.7874 0.4064)
			(stroke
				(width 0.1524)
				(type default)
			)
			(layer "F.SilkS")
		)
		(fp_line
			(start -0.7874 -0.4064)
			(end 0.7874 -0.4064)
			(stroke
				(width 0.1524)
				(type default)
			)
			(layer "F.SilkS")
		)
		(fp_line
			(start 0.7874 0.4064)
			(end -0.7874 0.4064)
			(stroke
				(width 0.1524)
				(type default)
			)
			(layer "F.SilkS")
		)
		(fp_line
			(start -0.7874 0.4064)
			(end -0.7874 -0.4064)
			(stroke
				(width 0.1524)
				(type default)
			)
			(layer "F.SilkS")
		)
		(fp_line
			(start -0.12065 -0.305054)
			(end -0.12065 -0.2794)
			(stroke
				(width 0.1)
				(type default)
			)
			(layer "F.Fab")
		)
		(fp_line
			(start -0.67945 -0.305054)
			(end -0.12065 -0.305054)
			(stroke
				(width 0.1)
				(type default)
			)
			(layer "F.Fab")
		)
		(fp_line
			(start 0.67945 -0.3048)
			(end 0.67945 0.3048)
			(stroke
				(width 0.1)
				(type default)
			)
			(layer "F.Fab")
		)
		(fp_line
			(start 0.12065 -0.3048)
			(end 0.67945 -0.3048)
			(stroke
				(width 0.1)
				(type default)
			)
			(layer "F.Fab")
		)
		(fp_line
			(start 0.12065 -0.2794)
			(end 0.12065 -0.3048)
			(stroke
				(width 0.1)
				(type default)
			)
			(layer "F.Fab")
		)
		(fp_line
			(start -0.12065 -0.2794)
			(end 0.12065 -0.2794)
			(stroke
				(width 0.1)
				(type default)
			)
			(layer "F.Fab")
		)
		(fp_line
			(start 0.120396 0.2794)
			(end -0.12065 0.2794)
			(stroke
				(width 0.1)
				(type default)
			)
			(layer "F.Fab")
		)
		(fp_line
			(start -0.12065 0.2794)
			(end -0.12065 0.3048)
			(stroke
				(width 0.1)
				(type default)
			)
			(layer "F.Fab")
		)
		(fp_line
			(start 0.67945 0.3048)
			(end 0.120396 0.3048)
			(stroke
				(width 0.1)
				(type default)
			)
			(layer "F.Fab")
		)
		(fp_line
			(start 0.120396 0.3048)
			(end 0.120396 0.2794)
			(stroke
				(width 0.1)
				(type default)
			)
			(layer "F.Fab")
		)
		(fp_line
			(start -0.12065 0.3048)
			(end -0.67945 0.3048)
			(stroke
				(width 0.1)
				(type default)
			)
			(layer "F.Fab")
		)
		(fp_line
			(start -0.67945 0.3048)
			(end -0.67945 -0.305054)
			(stroke
				(width 0.1)
				(type default)
			)
			(layer "F.Fab")
		)
		(pad "1" smd circle
			(at -0.40005 0 90)
			(size 0 0)
			(layers "F.Cu" "F.Mask" "F.Paste")
			(net "NC_PVCCINFAON_CPU1_ACSP3")
		)
		(pad "2" smd circle
			(at 0.40005 0 90)
			(size 0 0)
			(layers "F.Cu" "F.Mask" "F.Paste")
			(net "GND")
		)
	)
	(footprint ""
		(layer "F.Cu")
		(at 257.176524 -108.154216 90)
		(property "Reference" "R553"
			(at 0 0 90)
			(layer "F.SilkS")
			(hide yes)
			(effects
				(font
					(size 1.27 1.27)
				)
			)
		)
		(property "Value" ""
			(at 0 0 90)
			(layer "F.Fab")
			(effects
				(font
					(size 1.27 1.27)
				)
			)
		)
		(duplicate_pad_numbers_are_jumpers no)
		(fp_line
			(start 0.7874 -0.4064)
			(end 0.7874 0.4064)
			(stroke
				(width 0.1524)
				(type default)
			)
			(layer "F.SilkS")
		)
		(fp_line
			(start -0.7874 -0.4064)
			(end 0.7874 -0.4064)
			(stroke
				(width 0.1524)
				(type default)
			)
			(layer "F.SilkS")
		)
		(fp_line
			(start 0.7874 0.4064)
			(end -0.7874 0.4064)
			(stroke
				(width 0.1524)
				(type default)
			)
			(layer "F.SilkS")
		)
		(fp_line
			(start -0.7874 0.4064)
			(end -0.7874 -0.4064)
			(stroke
				(width 0.1524)
				(type default)
			)
			(layer "F.SilkS")
		)
		(fp_line
			(start -0.12065 -0.305054)
			(end -0.12065 -0.2794)
			(stroke
				(width 0.1)
				(type default)
			)
			(layer "F.Fab")
		)
		(fp_line
			(start -0.67945 -0.305054)
			(end -0.12065 -0.305054)
			(stroke
				(width 0.1)
				(type default)
			)
			(layer "F.Fab")
		)
		(fp_line
			(start 0.67945 -0.3048)
			(end 0.67945 0.3048)
			(stroke
				(width 0.1)
				(type default)
			)
			(layer "F.Fab")
		)
		(fp_line
			(start 0.12065 -0.3048)
			(end 0.67945 -0.3048)
			(stroke
				(width 0.1)
				(type default)
			)
			(layer "F.Fab")
		)
		(fp_line
			(start 0.12065 -0.2794)
			(end 0.12065 -0.3048)
			(stroke
				(width 0.1)
				(type default)
			)
			(layer "F.Fab")
		)
		(fp_line
			(start -0.12065 -0.2794)
			(end 0.12065 -0.2794)
			(stroke
				(width 0.1)
				(type default)
			)
			(layer "F.Fab")
		)
		(fp_line
			(start 0.120396 0.2794)
			(end -0.12065 0.2794)
			(stroke
				(width 0.1)
				(type default)
			)
			(layer "F.Fab")
		)
		(fp_line
			(start -0.12065 0.2794)
			(end -0.12065 0.3048)
			(stroke
				(width 0.1)
				(type default)
			)
			(layer "F.Fab")
		)
		(fp_line
			(start 0.67945 0.3048)
			(end 0.120396 0.3048)
			(stroke
				(width 0.1)
				(type default)
			)
			(layer "F.Fab")
		)
		(fp_line
			(start 0.120396 0.3048)
			(end 0.120396 0.2794)
			(stroke
				(width 0.1)
				(type default)
			)
			(layer "F.Fab")
		)
		(fp_line
			(start -0.12065 0.3048)
			(end -0.67945 0.3048)
			(stroke
				(width 0.1)
				(type default)
			)
			(layer "F.Fab")
		)
		(fp_line
			(start -0.67945 0.3048)
			(end -0.67945 -0.305054)
			(stroke
				(width 0.1)
				(type default)
			)
			(layer "F.Fab")
		)
		(pad "1" smd circle
			(at -0.40005 0 90)
			(size 0 0)
			(layers "F.Cu" "F.Mask" "F.Paste")
			(net "CLK_100M_CK440_PCH_EXTCLK_R_DP")
		)
		(pad "2" smd circle
			(at 0.40005 0 90)
			(size 0 0)
			(layers "F.Cu" "F.Mask" "F.Paste")
			(net "CLK_100M_CK440_PCH_EXTCLK_DP")
		)
	)
	(footprint ""
		(layer "F.Cu")
		(at 190.41364 -68.407788 180)
		(property "Reference" "PC2197"
			(at 0 0 180)
			(layer "F.SilkS")
			(hide yes)
			(effects
				(font
					(size 1.27 1.27)
				)
			)
		)
		(property "Value" ""
			(at 0 0 180)
			(layer "F.Fab")
			(effects
				(font
					(size 1.27 1.27)
				)
			)
		)
		(duplicate_pad_numbers_are_jumpers no)
		(fp_line
			(start 0.7874 0.4064)
			(end -0.7874 0.4064)
			(stroke
				(width 0.1524)
				(type default)
			)
			(layer "F.SilkS")
		)
		(fp_line
			(start 0.7874 -0.4064)
			(end 0.7874 0.4064)
			(stroke
				(width 0.1524)
				(type default)
			)
			(layer "F.SilkS")
		)
		(fp_line
			(start -0.7874 0.4064)
			(end -0.7874 -0.4064)
			(stroke
				(width 0.1524)
				(type default)
			)
			(layer "F.SilkS")
		)
		(fp_line
			(start -0.7874 -0.4064)
			(end 0.7874 -0.4064)
			(stroke
				(width 0.1524)
				(type default)
			)
			(layer "F.SilkS")
		)
		(fp_line
			(start 0.67945 0.3048)
			(end 0.120396 0.3048)
			(stroke
				(width 0.1)
				(type default)
			)
			(layer "F.Fab")
		)
		(fp_line
			(start 0.67945 -0.3048)
			(end 0.67945 0.3048)
			(stroke
				(width 0.1)
				(type default)
			)
			(layer "F.Fab")
		)
		(fp_line
			(start 0.12065 -0.2794)
			(end 0.12065 -0.3048)
			(stroke
				(width 0.1)
				(type default)
			)
			(layer "F.Fab")
		)
		(fp_line
			(start 0.12065 -0.3048)
			(end 0.67945 -0.3048)
			(stroke
				(width 0.1)
				(type default)
			)
			(layer "F.Fab")
		)
		(fp_line
			(start 0.120396 0.3048)
			(end 0.120396 0.2794)
			(stroke
				(width 0.1)
				(type default)
			)
			(layer "F.Fab")
		)
		(fp_line
			(start 0.120396 0.2794)
			(end -0.12065 0.2794)
			(stroke
				(width 0.1)
				(type default)
			)
			(layer "F.Fab")
		)
		(fp_line
			(start -0.12065 0.3048)
			(end -0.67945 0.3048)
			(stroke
				(width 0.1)
				(type default)
			)
			(layer "F.Fab")
		)
		(fp_line
			(start -0.12065 0.2794)
			(end -0.12065 0.3048)
			(stroke
				(width 0.1)
				(type default)
			)
			(layer "F.Fab")
		)
		(fp_line
			(start -0.12065 -0.2794)
			(end 0.12065 -0.2794)
			(stroke
				(width 0.1)
				(type default)
			)
			(layer "F.Fab")
		)
		(fp_line
			(start -0.12065 -0.305054)
			(end -0.12065 -0.2794)
			(stroke
				(width 0.1)
				(type default)
			)
			(layer "F.Fab")
		)
		(fp_line
			(start -0.67945 0.3048)
			(end -0.67945 -0.305054)
			(stroke
				(width 0.1)
				(type default)
			)
			(layer "F.Fab")
		)
		(fp_line
			(start -0.67945 -0.305054)
			(end -0.12065 -0.305054)
			(stroke
				(width 0.1)
				(type default)
			)
			(layer "F.Fab")
		)
		(pad "1" smd circle
			(at -0.40005 0 180)
			(size 0 0)
			(layers "F.Cu" "F.Mask" "F.Paste")
			(net "P3V3_E1S_MODE_0")
		)
		(pad "2" smd circle
			(at 0.40005 0 180)
			(size 0 0)
			(layers "F.Cu" "F.Mask" "F.Paste")
			(net "GND")
		)
	)
	(footprint ""
		(layer "F.Cu")
		(at 110.181136 -70.79361)
		(property "Reference" "D84"
			(at -54.939946 50.186082 90)
			(unlocked yes)
			(layer "F.SilkS")
			(effects
				(font
					(size 0.635 0.4064)
					(thickness 0.1524)
				)
				(justify left)
			)
		)
		(property "Value" ""
			(at 0 0 0)
			(layer "F.Fab")
			(effects
				(font
					(size 1.27 1.27)
				)
			)
		)
		(duplicate_pad_numbers_are_jumpers no)
		(fp_line
			(start -0.90678 0.4826)
			(end -0.90678 -0.4699)
			(stroke
				(width 0.1524)
				(type default)
			)
			(layer "F.SilkS")
		)
		(fp_line
			(start -0.89408 -0.4826)
			(end 0.90678 -0.4826)
			(stroke
				(width 0.1524)
				(type default)
			)
			(layer "F.SilkS")
		)
		(fp_line
			(start -0.79248 -0.4826)
			(end 1.03378 -0.4826)
			(stroke
				(width 0.1524)
				(type default)
			)
			(layer "F.SilkS")
		)
		(fp_line
			(start -0.64008 -0.4826)
			(end 1.16078 -0.4826)
			(stroke
				(width 0.1524)
				(type default)
			)
			(layer "F.SilkS")
		)
		(fp_line
			(start 0.90678 -0.4826)
			(end 0.90678 0.4826)
			(stroke
				(width 0.1524)
				(type default)
			)
			(layer "F.SilkS")
		)
		(fp_line
			(start 0.90678 0.4826)
			(end -0.90678 0.4826)
			(stroke
				(width 0.1524)
				(type default)
			)
			(layer "F.SilkS")
		)
		(fp_line
			(start 1.03378 -0.4826)
			(end 1.03378 0.4826)
			(stroke
				(width 0.1524)
				(type default)
			)
			(layer "F.SilkS")
		)
		(fp_line
			(start 1.03378 0.4826)
			(end -0.79248 0.4826)
			(stroke
				(width 0.1524)
				(type default)
			)
			(layer "F.SilkS")
		)
		(fp_line
			(start 1.16078 -0.4826)
			(end 1.16078 0.4826)
			(stroke
				(width 0.1524)
				(type default)
			)
			(layer "F.SilkS")
		)
		(fp_line
			(start 1.16078 0.4826)
			(end -0.64008 0.4826)
			(stroke
				(width 0.1524)
				(type default)
			)
			(layer "F.SilkS")
		)
		(fp_line
			(start -0.499872 -0.249936)
			(end 0.499872 -0.249936)
			(stroke
				(width 0.1)
				(type default)
			)
			(layer "F.Fab")
		)
		(fp_line
			(start -0.499872 0.249936)
			(end -0.499872 -0.249936)
			(stroke
				(width 0.1)
				(type default)
			)
			(layer "F.Fab")
		)
		(fp_line
			(start 0.499872 -0.249936)
			(end 0.499872 0.249936)
			(stroke
				(width 0.1)
				(type default)
			)
			(layer "F.Fab")
		)
		(fp_line
			(start 0.499872 0.249936)
			(end -0.499872 0.249936)
			(stroke
				(width 0.1)
				(type default)
			)
			(layer "F.Fab")
		)
		(pad "A" smd rect
			(at -0.47498 0)
			(size 0.6096 0.7112)
			(layers "F.Cu" "F.Mask" "F.Paste")
			(net "LED_PWRGD_PVCCINFAON_CPU1")
		)
		(pad "C" smd rect
			(at 0.47498 0)
			(size 0.6096 0.7112)
			(layers "F.Cu" "F.Mask" "F.Paste")
			(net "LED_PWRGD_PVCCINFAON_CPU1_D")
		)
	)
	(footprint ""
		(layer "F.Cu")
		(at 133.20903 -337.214718 -90)
		(property "Reference" "PC508_P1_5"
			(at 0 0 270)
			(layer "F.SilkS")
			(hide yes)
			(effects
				(font
					(size 1.27 1.27)
				)
			)
		)
		(property "Value" ""
			(at 0 0 270)
			(layer "F.Fab")
			(effects
				(font
					(size 1.27 1.27)
				)
			)
		)
		(duplicate_pad_numbers_are_jumpers no)
		(fp_line
			(start -0.7874 0.4064)
			(end -0.7874 -0.4064)
			(stroke
				(width 0.1524)
				(type default)
			)
			(layer "F.SilkS")
		)
		(fp_line
			(start 0.7874 0.4064)
			(end -0.7874 0.4064)
			(stroke
				(width 0.1524)
				(type default)
			)
			(layer "F.SilkS")
		)
		(fp_line
			(start -0.7874 -0.4064)
			(end 0.7874 -0.4064)
			(stroke
				(width 0.1524)
				(type default)
			)
			(layer "F.SilkS")
		)
		(fp_line
			(start 0.7874 -0.4064)
			(end 0.7874 0.4064)
			(stroke
				(width 0.1524)
				(type default)
			)
			(layer "F.SilkS")
		)
		(fp_line
			(start -0.67945 0.3048)
			(end -0.67945 -0.305054)
			(stroke
				(width 0.1)
				(type default)
			)
			(layer "F.Fab")
		)
		(fp_line
			(start -0.12065 0.3048)
			(end -0.67945 0.3048)
			(stroke
				(width 0.1)
				(type default)
			)
			(layer "F.Fab")
		)
		(fp_line
			(start 0.120396 0.3048)
			(end 0.120396 0.2794)
			(stroke
				(width 0.1)
				(type default)
			)
			(layer "F.Fab")
		)
		(fp_line
			(start 0.67945 0.3048)
			(end 0.120396 0.3048)
			(stroke
				(width 0.1)
				(type default)
			)
			(layer "F.Fab")
		)
		(fp_line
			(start -0.12065 0.2794)
			(end -0.12065 0.3048)
			(stroke
				(width 0.1)
				(type default)
			)
			(layer "F.Fab")
		)
		(fp_line
			(start 0.120396 0.2794)
			(end -0.12065 0.2794)
			(stroke
				(width 0.1)
				(type default)
			)
			(layer "F.Fab")
		)
		(fp_line
			(start -0.12065 -0.2794)
			(end 0.12065 -0.2794)
			(stroke
				(width 0.1)
				(type default)
			)
			(layer "F.Fab")
		)
		(fp_line
			(start 0.12065 -0.2794)
			(end 0.12065 -0.3048)
			(stroke
				(width 0.1)
				(type default)
			)
			(layer "F.Fab")
		)
		(fp_line
			(start 0.12065 -0.3048)
			(end 0.67945 -0.3048)
			(stroke
				(width 0.1)
				(type default)
			)
			(layer "F.Fab")
		)
		(fp_line
			(start 0.67945 -0.3048)
			(end 0.67945 0.3048)
			(stroke
				(width 0.1)
				(type default)
			)
			(layer "F.Fab")
		)
		(fp_line
			(start -0.67945 -0.305054)
			(end -0.12065 -0.305054)
			(stroke
				(width 0.1)
				(type default)
			)
			(layer "F.Fab")
		)
		(fp_line
			(start -0.12065 -0.305054)
			(end -0.12065 -0.2794)
			(stroke
				(width 0.1)
				(type default)
			)
			(layer "F.Fab")
		)
		(pad "1" smd circle
			(at -0.40005 0 270)
			(size 0 0)
			(layers "F.Cu" "F.Mask" "F.Paste")
			(net "SW_P12V_PVCCIN_CPU1_FLT")
		)
		(pad "2" smd circle
			(at 0.40005 0 270)
			(size 0 0)
			(layers "F.Cu" "F.Mask" "F.Paste")
			(net "GND")
		)
	)
	(footprint ""
		(layer "F.Cu")
		(at 111.24946 -418.027358 90)
		(property "Reference" "R2660"
			(at 0 0 90)
			(layer "F.SilkS")
			(hide yes)
			(effects
				(font
					(size 1.27 1.27)
				)
			)
		)
		(property "Value" ""
			(at 0 0 90)
			(layer "F.Fab")
			(effects
				(font
					(size 1.27 1.27)
				)
			)
		)
		(duplicate_pad_numbers_are_jumpers no)
		(fp_line
			(start 0.7874 -0.4064)
			(end 0.7874 0.03556)
			(stroke
				(width 0.1524)
				(type default)
			)
			(layer "F.SilkS")
		)
		(fp_line
			(start -0.7874 -0.4064)
			(end 0.7874 -0.4064)
			(stroke
				(width 0.1524)
				(type default)
			)
			(layer "F.SilkS")
		)
		(fp_line
			(start -0.7874 -0.0127)
			(end -0.7874 -0.4064)
			(stroke
				(width 0.1524)
				(type default)
			)
			(layer "F.SilkS")
		)
		(fp_line
			(start 0.35941 0.4064)
			(end -0.39751 0.4064)
			(stroke
				(width 0.1524)
				(type default)
			)
			(layer "F.SilkS")
		)
		(fp_line
			(start -0.12065 -0.305054)
			(end -0.12065 -0.2794)
			(stroke
				(width 0.1)
				(type default)
			)
			(layer "F.Fab")
		)
		(fp_line
			(start -0.67945 -0.305054)
			(end -0.12065 -0.305054)
			(stroke
				(width 0.1)
				(type default)
			)
			(layer "F.Fab")
		)
		(fp_line
			(start 0.67945 -0.3048)
			(end 0.67945 0.3048)
			(stroke
				(width 0.1)
				(type default)
			)
			(layer "F.Fab")
		)
		(fp_line
			(start 0.12065 -0.3048)
			(end 0.67945 -0.3048)
			(stroke
				(width 0.1)
				(type default)
			)
			(layer "F.Fab")
		)
		(fp_line
			(start 0.12065 -0.2794)
			(end 0.12065 -0.3048)
			(stroke
				(width 0.1)
				(type default)
			)
			(layer "F.Fab")
		)
		(fp_line
			(start -0.12065 -0.2794)
			(end 0.12065 -0.2794)
			(stroke
				(width 0.1)
				(type default)
			)
			(layer "F.Fab")
		)
		(fp_line
			(start 0.120396 0.2794)
			(end -0.12065 0.2794)
			(stroke
				(width 0.1)
				(type default)
			)
			(layer "F.Fab")
		)
		(fp_line
			(start -0.12065 0.2794)
			(end -0.12065 0.3048)
			(stroke
				(width 0.1)
				(type default)
			)
			(layer "F.Fab")
		)
		(fp_line
			(start 0.67945 0.3048)
			(end 0.120396 0.3048)
			(stroke
				(width 0.1)
				(type default)
			)
			(layer "F.Fab")
		)
		(fp_line
			(start 0.120396 0.3048)
			(end 0.120396 0.2794)
			(stroke
				(width 0.1)
				(type default)
			)
			(layer "F.Fab")
		)
		(fp_line
			(start -0.12065 0.3048)
			(end -0.67945 0.3048)
			(stroke
				(width 0.1)
				(type default)
			)
			(layer "F.Fab")
		)
		(fp_line
			(start -0.67945 0.3048)
			(end -0.67945 -0.305054)
			(stroke
				(width 0.1)
				(type default)
			)
			(layer "F.Fab")
		)
		(pad "1" smd circle
			(at -0.40005 0 90)
			(size 0 0)
			(layers "F.Cu" "F.Mask" "F.Paste")
			(net "CLK_100M_SWB_R_DN")
		)
		(pad "2" smd circle
			(at 0.40005 0 90)
			(size 0 0)
			(layers "F.Cu" "F.Mask" "F.Paste")
			(net "CLK_100M_SWB_DN")
		)
	)
)
